# T6G (Grand Teton) — schematic netlist excerpt (pin names and nets, part order shuffled) for the footprints in the layout excerpt that follows; sources: Cadence DE-HDL packaged netlist, KiCad conversion of 04192023_DAF0TMB3IC0_F0TG_MB_C_brd_V02_OCP.brd

R576  Q_RES  0 5% CHIP  pkg 0402LF  page 134 : A = HP_LVC3_OCP_V3_1_PRSNT2_N_R ; B = HP_LVC3_OCP_SFF_PRSNT2_N
R391  Q_RES  2.2K 5% CHIP  pkg 0402LF  page 27 : A = P3V3_AUX ; B = CPU0_SP5R3

(kicad_pcb
	(version 20260206)
	(generator "pcbnew")
	(generator_version "10.0")
	(general
		(thickness 1.6)
		(legacy_teardrops no)
	)
	(paper "A4")
	(title_block
		(title "04192023_DAF0TMB3IC0_F0TG_MB_C_brd_V02_OCP.brd")
		(comment 1 "Grand Teton / footprints 429-430 of 8354")
	)
	(layers
		(0 "F.Cu" signal "TOP")
		(4 "In1.Cu" signal "GND")
		(6 "In2.Cu" signal "IN1")
		(8 "In3.Cu" signal "GND1")
		(10 "In4.Cu" signal "IN2")
		(12 "In5.Cu" signal "GND2")
		(14 "In6.Cu" signal "IN3")
		(16 "In7.Cu" signal "GND3")
		(18 "In8.Cu" signal "VCC")
		(20 "In9.Cu" signal "VCC1")
		(22 "In10.Cu" signal "GND4")
		(24 "In11.Cu" signal "IN4")
		(26 "In12.Cu" signal "GND5")
		(28 "In13.Cu" signal "IN5")
		(30 "In14.Cu" signal "GND6")
		(32 "In15.Cu" signal "IN6")
		(34 "In16.Cu" signal "GND7")
		(2 "B.Cu" signal "BOTTOM")
		(9 "F.Adhes" user "F.Adhesive")
		(11 "B.Adhes" user "B.Adhesive")
		(13 "F.Paste" user "Package Geometry/Pastemask Top")
		(15 "B.Paste" user "Package Geometry/Pastemask Bottom")
		(5 "F.SilkS" user "Ref Des/Silkscreen Top")
		(7 "B.SilkS" user "Ref Des/Silkscreen Bottom")
		(1 "F.Mask" user "Board Geometry/Soldermask Top")
		(3 "B.Mask" user "Board Geometry/Soldermask Bottom")
		(17 "Dwgs.User" user "User.Drawings")
		(19 "Cmts.User" user "User.Comments")
		(21 "Eco1.User" user "User.Eco1")
		(23 "Eco2.User" user "User.Eco2")
		(25 "Edge.Cuts" user "Board Geometry/Outline")
		(27 "Margin" user)
		(31 "F.CrtYd" user "Package Geometry/Place Bound Top")
		(29 "B.CrtYd" user "Package Geometry/Place Bound Bottom")
		(35 "F.Fab" user "Ref Des/Assembly Top")
		(33 "B.Fab" user "Ref Des/Assembly Bottom")
	)
	(footprint ""
		(layer "F.Cu")
		(at 192.913 -96.103948 90)
		(property "Reference" "R391"
			(at 0 0 90)
			(layer "F.SilkS")
			(hide yes)
			(effects
				(font
					(size 1.27 1.27)
				)
			)
		)
		(property "Value" ""
			(at 0 0 90)
			(layer "F.Fab")
			(effects
				(font
					(size 1.27 1.27)
				)
			)
		)
		(duplicate_pad_numbers_are_jumpers no)
		(fp_line
			(start 0.7874 -0.4064)
			(end 0.7874 0.4064)
			(stroke
				(width 0.1524)
				(type default)
			)
			(layer "F.SilkS")
		)
		(fp_line
			(start -0.7874 -0.4064)
			(end 0.7874 -0.4064)
			(stroke
				(width 0.1524)
				(type default)
			)
			(layer "F.SilkS")
		)
		(fp_line
			(start 0.7874 0.4064)
			(end -0.7874 0.4064)
			(stroke
				(width 0.1524)
				(type default)
			)
			(layer "F.SilkS")
		)
		(fp_line
			(start -0.7874 0.4064)
			(end -0.7874 -0.4064)
			(stroke
				(width 0.1524)
				(type default)
			)
			(layer "F.SilkS")
		)
		(fp_line
			(start -0.12065 -0.305054)
			(end -0.12065 -0.2794)
			(stroke
				(width 0.1)
				(type default)
			)
			(layer "F.Fab")
		)
		(fp_line
			(start -0.67945 -0.305054)
			(end -0.12065 -0.305054)
			(stroke
				(width 0.1)
				(type default)
			)
			(layer "F.Fab")
		)
		(fp_line
			(start 0.67945 -0.3048)
			(end 0.67945 0.3048)
			(stroke
				(width 0.1)
				(type default)
			)
			(layer "F.Fab")
		)
		(fp_line
			(start 0.12065 -0.3048)
			(end 0.67945 -0.3048)
			(stroke
				(width 0.1)
				(type default)
			)
			(layer "F.Fab")
		)
		(fp_line
			(start 0.12065 -0.2794)
			(end 0.12065 -0.3048)
			(stroke
				(width 0.1)
				(type default)
			)
			(layer "F.Fab")
		)
		(fp_line
			(start -0.12065 -0.2794)
			(end 0.12065 -0.2794)
			(stroke
				(width 0.1)
				(type default)
			)
			(layer "F.Fab")
		)
		(fp_line
			(start 0.120396 0.2794)
			(end -0.12065 0.2794)
			(stroke
				(width 0.1)
				(type default)
			)
			(layer "F.Fab")
		)
		(fp_line
			(start -0.12065 0.2794)
			(end -0.12065 0.3048)
			(stroke
				(width 0.1)
				(type default)
			)
			(layer "F.Fab")
		)
		(fp_line
			(start 0.67945 0.3048)
			(end 0.120396 0.3048)
			(stroke
				(width 0.1)
				(type default)
			)
			(layer "F.Fab")
		)
		(fp_line
			(start 0.120396 0.3048)
			(end 0.120396 0.2794)
			(stroke
				(width 0.1)
				(type default)
			)
			(layer "F.Fab")
		)
		(fp_line
			(start -0.12065 0.3048)
			(end -0.67945 0.3048)
			(stroke
				(width 0.1)
				(type default)
			)
			(layer "F.Fab")
		)
		(fp_line
			(start -0.67945 0.3048)
			(end -0.67945 -0.305054)
			(stroke
				(width 0.1)
				(type default)
			)
			(layer "F.Fab")
		)
		(pad "1" smd circle
			(at -0.40005 0 90)
			(size 0 0)
			(layers "F.Cu" "F.Mask" "F.Paste")
			(net "P3V3_AUX")
		)
		(pad "2" smd circle
			(at 0.40005 0 90)
			(size 0 0)
			(layers "F.Cu" "F.Mask" "F.Paste")
			(net "CPU0_SP5R3")
		)
	)
	(footprint ""
		(layer "F.Cu")
		(at 461.592168 -109.646212)
		(property "Reference" "R576"
			(at 0 0 0)
			(layer "F.SilkS")
			(hide yes)
			(effects
				(font
					(size 1.27 1.27)
				)
			)
		)
		(property "Value" ""
			(at 0 0 0)
			(layer "F.Fab")
			(effects
				(font
					(size 1.27 1.27)
				)
			)
		)
		(duplicate_pad_numbers_are_jumpers no)
		(fp_line
			(start -0.7874 -0.4064)
			(end 0.7874 -0.4064)
			(stroke
				(width 0.1524)
				(type default)
			)
			(layer "F.SilkS")
		)
		(fp_line
			(start -0.7874 0.4064)
			(end -0.7874 -0.4064)
			(stroke
				(width 0.1524)
				(type default)
			)
			(layer "F.SilkS")
		)
		(fp_line
			(start 0.7874 -0.4064)
			(end 0.7874 0.4064)
			(stroke
				(width 0.1524)
				(type default)
			)
			(layer "F.SilkS")
		)
		(fp_line
			(start 0.7874 0.4064)
			(end -0.7874 0.4064)
			(stroke
				(width 0.1524)
				(type default)
			)
			(layer "F.SilkS")
		)
		(fp_line
			(start -0.67945 -0.305054)
			(end -0.12065 -0.305054)
			(stroke
				(width 0.1)
				(type default)
			)
			(layer "F.Fab")
		)
		(fp_line
			(start -0.67945 0.3048)
			(end -0.67945 -0.305054)
			(stroke
				(width 0.1)
				(type default)
			)
			(layer "F.Fab")
		)
		(fp_line
			(start -0.12065 -0.305054)
			(end -0.12065 -0.2794)
			(stroke
				(width 0.1)
				(type default)
			)
			(layer "F.Fab")
		)
		(fp_line
			(start -0.12065 -0.2794)
			(end 0.12065 -0.2794)
			(stroke
				(width 0.1)
				(type default)
			)
			(layer "F.Fab")
		)
		(fp_line
			(start -0.12065 0.2794)
			(end -0.12065 0.3048)
			(stroke
				(width 0.1)
				(type default)
			)
			(layer "F.Fab")
		)
		(fp_line
			(start -0.12065 0.3048)
			(end -0.67945 0.3048)
			(stroke
				(width 0.1)
				(type default)
			)
			(layer "F.Fab")
		)
		(fp_line
			(start 0.120396 0.2794)
			(end -0.12065 0.2794)
			(stroke
				(width 0.1)
				(type default)
			)
			(layer "F.Fab")
		)
		(fp_line
			(start 0.120396 0.3048)
			(end 0.120396 0.2794)
			(stroke
				(width 0.1)
				(type default)
			)
			(layer "F.Fab")
		)
		(fp_line
			(start 0.12065 -0.3048)
			(end 0.67945 -0.3048)
			(stroke
				(width 0.1)
				(type default)
			)
			(layer "F.Fab")
		)
		(fp_line
			(start 0.12065 -0.2794)
			(end 0.12065 -0.3048)
			(stroke
				(width 0.1)
				(type default)
			)
			(layer "F.Fab")
		)
		(fp_line
			(start 0.67945 -0.3048)
			(end 0.67945 0.3048)
			(stroke
				(width 0.1)
				(type default)
			)
			(layer "F.Fab")
		)
		(fp_line
			(start 0.67945 0.3048)
			(end 0.120396 0.3048)
			(stroke
				(width 0.1)
				(type default)
			)
			(layer "F.Fab")
		)
		(pad "1" smd circle
			(at -0.40005 0)
			(size 0 0)
			(layers "F.Cu" "F.Mask" "F.Paste")
			(net "HP_LVC3_OCP_V3_1_PRSNT2_N_R")
		)
		(pad "2" smd circle
			(at 0.40005 0)
			(size 0 0)
			(layers "F.Cu" "F.Mask" "F.Paste")
			(net "HP_LVC3_OCP_SFF_PRSNT2_N")
		)
	)
)
